FILE_TYPE = MULTI_PHYS_TABLE;

PART 'SCONN20_HSU2101L00007H'

{========================================================================================}
:VALUE                      | PART_TYPE | MATERIAL | PART_NUMBER    = STANDARD        | LIFECYCLE      | PART_NUMBER   | JEDEC_TYPE      | DESCRIPTION                              | MANUFTR | MANUF_PN           | RD_CMPLS_LVL | CMPLS_LVL | CLASS | DIP_SMD | FROM_PJ   | DATA                       | FP_ECN                 | EE_CHECK_LIST | CREATOR | CREATEDAY  | PSL | STATUS | ESD_CDM | ESD_HBM | ESD_MM | MSD | PIN_LENGTH_LONG_PIN | PIN_LENGTH_SHORT_PIN ;
{========================================================================================}
 'SCONN20_HSU2101-L0000-7H' | 'SMLF'    | 'IO'     | 'DFHD20MS153'(!) = ''               | ''               | 'DFHD20MS153' |'HEADER2X10SXK'| 'CONN SMD HEADER 20P 2R MS(P1.27,H6.14)' | 'FOX'   | 'HSU2101-L0000-7H' | 'EP(V1)'     | 'EP(V1)'  | 'IO'  | ''      | 'T6G-JAY' | 'FOX_HSU2101-L0000-7H.pdf' | 'HSU2101-L0000-7H.msg' | ''            | ''      | '20210719' | ''  | ''     | ''      | ''      | ''     | ''  | '0 MILS'            | '0 MILS'            
 'SCONN20_HSU2101-L0000-7H' | 'SMLF'    | 'EMPTY'  | 'DFHD20MS153'(!) = ''               | ''               | 'DFHD20MS153' |'HEADER2X10SXK'| 'CONN SMD HEADER 20P 2R MS(P1.27,H6.14)' | 'FOX'   | 'HSU2101-L0000-7H' | 'EP(V1)'     | 'EP(V1)'  | 'IO'  | ''      | 'T6G-JAY' | 'FOX_HSU2101-L0000-7H.pdf' | 'HSU2101-L0000-7H.msg' | ''            | ''      | '20210719' | ''  | ''     | ''      | ''      | ''     | ''  | '0 MILS'            | '0 MILS'            

END_PART

END.

